(kicad_pcb
	(version 20221018)
	(generator pcbnew)
	(general
    (thickness 1.518)
  )
	(paper "A4")
	(title_block
    (title "Kria K26 Devboard")
    (date "2024-03-26")
    (rev "1.2.5")
    (comment 1 "www.antmicro.com")
    (comment 2 "Antmicro Ltd.")
		(comment 9 "footprints 597-603 of 660")
	)
	(layers
    (0 "F.Cu" mixed)
    (1 "In1.Cu" power)
    (2 "In2.Cu" mixed)
    (3 "In3.Cu" power)
    (4 "In4.Cu" mixed)
    (5 "In5.Cu" power)
    (6 "In6.Cu" mixed)
    (31 "B.Cu" power)
    (32 "B.Adhes" user "B.Adhesive")
    (33 "F.Adhes" user "F.Adhesive")
    (34 "B.Paste" user)
    (35 "F.Paste" user)
    (36 "B.SilkS" user "B.Silkscreen")
    (37 "F.SilkS" user "F.Silkscreen")
    (38 "B.Mask" user)
    (39 "F.Mask" user)
    (40 "Dwgs.User" user "User.Drawings")
    (41 "Cmts.User" user "User.Comments")
    (42 "Eco1.User" user "User.Eco1")
    (43 "Eco2.User" user "User.Eco2")
    (44 "Edge.Cuts" user)
    (45 "Margin" user)
    (46 "B.CrtYd" user "B.Courtyard")
    (47 "F.CrtYd" user "F.Courtyard")
    (48 "B.Fab" user)
    (49 "F.Fab" user)
  )
	(footprint "kria-k26-devboard-footprints:R_0402_1005Metric" (layer "B.Cu")
    (at 127.65 84.88 180)
    (descr "Resistor SMD 0402")
    (tags "resistor SMD 0402")
    (property "Author" "Antmicro")
    (property "License" "Apache-2.0")
    (property "MPN" "CR0402-FX-5111GLF")
    (property "Manufacturer" "Bourns")
    (property "Sheetfile" "usb.kicad_sch")
    (property "Sheetname" "USB")
    (property "Tolerance" "1%")
    (property "Val" "5k11")
    (property "ki_description" "5k11 resistor in 0402 package with 1% tolerance")
    (attr smd)
    (fp_text reference "R62" (at 0.9 -0.38) (layer "B.SilkS")
        (effects (font (size 0.7 0.7) (thickness 0.15)) (justify left bottom mirror))
    )
    (fp_text value "R_5k11_0402" (at 0 -1.4) (layer "B.Fab") hide
        (effects (font (size 0.7 0.7) (thickness 0.15)) (justify left bottom mirror))
    )
    (fp_text user "Author: Antmicro" (at -0.95 -4.169) (layer "B.Fab") hide
        (effects (font (size 0.7 0.7) (thickness 0.15)) (justify left bottom mirror))
    )
    (fp_text user "${REFERENCE}" (at -0.95 -3.168) (layer "B.Fab") hide
        (effects (font (size 0.7 0.7) (thickness 0.15)) (justify left bottom mirror))
    )
    (fp_text user "License: Apache-2.0" (at -0.95 -5.169) (layer "B.Fab") hide
        (effects (font (size 0.7 0.7) (thickness 0.15)) (justify left bottom mirror))
    )
    (fp_rect (start -0.93 0.47) (end 0.93 -0.47)
      (stroke (width 0.05) (type solid)) (fill none) (layer "B.CrtYd"))
    (fp_rect (start -0.5 0.25) (end 0.5 -0.25)
      (stroke (width 0.15) (type solid)) (fill none) (layer "B.Fab"))
    (pad "1" smd roundrect (at -0.485 0 180) (size 0.59 0.64) (layers "B.Cu" "B.Paste" "B.Mask") (roundrect_rratio 0.25)
      (net 665 "Net-(U17-DP1_CC1)") (pintype "passive"))
    (pad "2" smd roundrect (at 0.485 0 180) (size 0.59 0.64) (layers "B.Cu" "B.Paste" "B.Mask") (roundrect_rratio 0.25)
      (net 1 "GND") (pintype "passive"))
  )
	(footprint "kria-k26-devboard-footprints:SOT-416" (layer "B.Cu")
    (at 100.6 89.2)
    (descr "SOT-416")
    (tags "SOT-416")
    (property "Author" "Antmicro")
    (property "License" "Apache-2.0")
    (property "MPN" "DTC014TEBTL")
    (property "Manufacturer" "ROHM Semiconductor")
    (property "Sheetfile" "k26_som.kicad_sch")
    (property "Sheetname" "Xilinx K26 SOM")
    (property "ki_description" "Digital NPN Transistor, 10k/NONE, EMT-3")
    (attr smd)
    (fp_text reference "Q7" (at 0.9 1.92 180) (layer "B.SilkS")
        (effects (font (size 0.7 0.7) (thickness 0.15)) (justify left bottom mirror))
    )
    (fp_text value "DTC014T_SOT-416" (at 0 -2 180) (layer "B.Fab") hide
        (effects (font (size 0.7 0.7) (thickness 0.15)) (justify left bottom mirror))
    )
    (fp_text user "${REFERENCE}" (at -1 -3.4 180) (layer "B.Fab") hide
        (effects (font (size 0.7 0.7) (thickness 0.15)) (justify left bottom mirror))
    )
    (fp_text user "Author: Antmicro" (at -1 -4.602 180) (layer "B.Fab") hide
        (effects (font (size 0.7 0.7) (thickness 0.15)) (justify left bottom mirror))
    )
    (fp_text user "License: Apache-2.0" (at -1 -5.802 180) (layer "B.Fab") hide
        (effects (font (size 0.7 0.7) (thickness 0.15)) (justify left bottom mirror))
    )
    (fp_line (start -0.5 0.15) (end -0.5 -0.15)
      (stroke (width 0.15) (type solid)) (layer "B.SilkS"))
    (fp_line (start 0.5 -0.9) (end -0.5 -0.9)
      (stroke (width 0.15) (type solid)) (layer "B.SilkS"))
    (fp_line (start 0.5 -0.9) (end 0.5 -0.7)
      (stroke (width 0.15) (type solid)) (layer "B.SilkS"))
    (fp_line (start 0.508 0.9) (end -0.5 0.9)
      (stroke (width 0.15) (type solid)) (layer "B.SilkS"))
    (fp_line (start 0.508 0.9) (end 0.508 0.592)
      (stroke (width 0.15) (type solid)) (layer "B.SilkS"))
    (fp_rect (start -1 1.05) (end 1 -1.05)
      (stroke (width 0.05) (type solid)) (fill none) (layer "B.CrtYd"))
    (fp_line (start -0.05 0.9) (end -0.45 0.5)
      (stroke (width 0.15) (type solid)) (layer "B.Fab"))
    (fp_rect (start 0.45 -0.9) (end -0.45 0.9)
      (stroke (width 0.15) (type solid)) (fill none) (layer "B.Fab"))
    (pad "1" smd rect (at -0.652 0.5) (size 0.6 0.5) (layers "B.Cu" "B.Paste" "B.Mask")
      (net 431 "Net-(Q19-C)") (pinfunction "B") (pintype "input"))
    (pad "2" smd rect (at -0.652 -0.498) (size 0.6 0.5) (layers "B.Cu" "B.Paste" "B.Mask")
      (net 1 "GND") (pinfunction "E") (pintype "passive"))
    (pad "3" smd rect (at 0.65 0) (size 0.6 0.5) (layers "B.Cu" "B.Paste" "B.Mask")
      (net 430 "Net-(Q6-G)") (pinfunction "C") (pintype "passive"))
  )
	(footprint "kria-k26-devboard-footprints:R_0402_1005Metric" (layer "B.Cu")
    (at 101 87.45 180)
    (descr "Resistor SMD 0402")
    (tags "resistor SMD 0402")
    (property "Author" "Antmicro")
    (property "License" "Apache-2.0")
    (property "MPN" "CR0402-FX-1003GLF")
    (property "Manufacturer" "Bourns")
    (property "Sheetfile" "k26_som.kicad_sch")
    (property "Sheetname" "Xilinx K26 SOM")
    (property "Tolerance" "1%")
    (property "Val" "100k")
    (property "ki_description" "100k resistor in 0402 package with 1% tolerance")
    (attr smd)
    (fp_text reference "R83" (at -1.12 0.62) (layer "B.SilkS")
        (effects (font (size 0.7 0.7) (thickness 0.15)) (justify left bottom mirror))
    )
    (fp_text value "R_100k_0402" (at 0 -1.4) (layer "B.Fab") hide
        (effects (font (size 0.7 0.7) (thickness 0.15)) (justify left bottom mirror))
    )
    (fp_text user "${REFERENCE}" (at -0.95 -3.168) (layer "B.Fab") hide
        (effects (font (size 0.7 0.7) (thickness 0.15)) (justify left bottom mirror))
    )
    (fp_text user "License: Apache-2.0" (at -0.95 -5.169) (layer "B.Fab") hide
        (effects (font (size 0.7 0.7) (thickness 0.15)) (justify left bottom mirror))
    )
    (fp_text user "Author: Antmicro" (at -0.95 -4.169) (layer "B.Fab") hide
        (effects (font (size 0.7 0.7) (thickness 0.15)) (justify left bottom mirror))
    )
    (fp_rect (start -0.93 0.47) (end 0.93 -0.47)
      (stroke (width 0.05) (type solid)) (fill none) (layer "B.CrtYd"))
    (fp_rect (start -0.5 0.25) (end 0.5 -0.25)
      (stroke (width 0.15) (type solid)) (fill none) (layer "B.Fab"))
    (pad "1" smd roundrect (at -0.485 0 180) (size 0.59 0.64) (layers "B.Cu" "B.Paste" "B.Mask") (roundrect_rratio 0.25)
      (net 306 "USB_5V") (pintype "passive"))
    (pad "2" smd roundrect (at 0.485 0 180) (size 0.59 0.64) (layers "B.Cu" "B.Paste" "B.Mask") (roundrect_rratio 0.25)
      (net 430 "Net-(Q6-G)") (pintype "passive"))
  )
	(footprint "kria-k26-devboard-footprints:SOT-23-3" (layer "B.Cu")
    (at 103.8 88.4)
    (property "Author" "Antmicro")
    (property "License" "Apache-2.0")
    (property "MPN" "PJA3441_R1_00001")
    (property "Manufacturer" "Panjit")
    (property "Sheetfile" "k26_som.kicad_sch")
    (property "Sheetname" "Xilinx K26 SOM")
    (property "ki_description" "MOSFET 40V P-Channel Enhancement Mode MOSFET")
    (attr smd)
    (fp_text reference "Q6" (at 0.21 2.49 180) (layer "B.SilkS")
        (effects (font (size 0.7 0.7) (thickness 0.15)) (justify left bottom mirror))
    )
    (fp_text value "PJA3441" (at -1.9 -2.7 180) (layer "B.Fab") hide
        (effects (font (size 0.7 0.7) (thickness 0.15)) (justify left bottom mirror))
    )
    (fp_text user "License: Apache-2.0" (at -1.8 -6.8 180) (layer "B.Fab") hide
        (effects (font (size 0.7 0.7) (thickness 0.15)) (justify left bottom mirror))
    )
    (fp_text user "Author: Antmicro" (at -1.837 -5.3 180) (layer "B.Fab") hide
        (effects (font (size 0.7 0.7) (thickness 0.15)) (justify left bottom mirror))
    )
    (fp_text user "${REFERENCE}" (at -1.837 -4 180) (layer "B.Fab") hide
        (effects (font (size 0.7 0.7) (thickness 0.15)) (justify left bottom mirror))
    )
    (fp_line (start -1.45 1.35) (end -0.85 1.35)
      (stroke (width 0.15) (type solid)) (layer "B.SilkS"))
    (fp_line (start -0.85 1.35) (end -0.7 1.5)
      (stroke (width 0.15) (type solid)) (layer "B.SilkS"))
    (fp_line (start -0.7 -1.5) (end -0.7 -1.35)
      (stroke (width 0.15) (type solid)) (layer "B.SilkS"))
    (fp_line (start 0.7 -1.5) (end -0.7 -1.5)
      (stroke (width 0.15) (type solid)) (layer "B.SilkS"))
    (fp_line (start 0.7 -0.4) (end 0.7 -1.5)
      (stroke (width 0.15) (type solid)) (layer "B.SilkS"))
    (fp_line (start 0.7 0.4) (end 0.7 1.5)
      (stroke (width 0.15) (type solid)) (layer "B.SilkS"))
    (fp_line (start 0.7 1.5) (end -0.7 1.5)
      (stroke (width 0.15) (type solid)) (layer "B.SilkS"))
    (fp_line (start -1.75 -1.4) (end -1.75 -0.5)
      (stroke (width 0.05) (type solid)) (layer "B.CrtYd"))
    (fp_line (start -1.75 -0.5) (end -0.85 -0.5)
      (stroke (width 0.05) (type solid)) (layer "B.CrtYd"))
    (fp_line (start -1.75 0.5) (end -1.75 1.4)
      (stroke (width 0.05) (type solid)) (layer "B.CrtYd"))
    (fp_line (start -0.9 1.4) (end -1.75 1.4)
      (stroke (width 0.05) (type solid)) (layer "B.CrtYd"))
    (fp_line (start -0.9 1.6) (end -0.9 1.4)
      (stroke (width 0.05) (type solid)) (layer "B.CrtYd"))
    (fp_line (start -0.9 1.6) (end 0.825 1.6)
      (stroke (width 0.05) (type solid)) (layer "B.CrtYd"))
    (fp_line (start -0.85 -1.65) (end -0.85 -1.4)
      (stroke (width 0.05) (type solid)) (layer "B.CrtYd"))
    (fp_line (start -0.85 -1.4) (end -1.75 -1.4)
      (stroke (width 0.05) (type solid)) (layer "B.CrtYd"))
    (fp_line (start -0.85 -0.5) (end -0.85 0.5)
      (stroke (width 0.05) (type solid)) (layer "B.CrtYd"))
    (fp_line (start -0.85 0.5) (end -1.75 0.5)
      (stroke (width 0.05) (type solid)) (layer "B.CrtYd"))
    (fp_line (start 0.825 0.45) (end 1.75 0.45)
      (stroke (width 0.05) (type solid)) (layer "B.CrtYd"))
    (fp_line (start 0.825 1.6) (end 0.825 0.45)
      (stroke (width 0.05) (type solid)) (layer "B.CrtYd"))
    (fp_line (start 0.85 -1.65) (end -0.85 -1.65)
      (stroke (width 0.05) (type solid)) (layer "B.CrtYd"))
    (fp_line (start 0.85 -0.45) (end 0.85 -1.65)
      (stroke (width 0.05) (type solid)) (layer "B.CrtYd"))
    (fp_line (start 1.75 -0.45) (end 0.85 -0.45)
      (stroke (width 0.05) (type solid)) (layer "B.CrtYd"))
    (fp_line (start 1.75 0.45) (end 1.75 -0.45)
      (stroke (width 0.05) (type solid)) (layer "B.CrtYd"))
    (fp_line (start -0.712 -1.519) (end 0.688 -1.519)
      (stroke (width 0.15) (type solid)) (layer "B.Fab"))
    (fp_line (start -0.712 1.325) (end -0.712 -1.523)
      (stroke (width 0.15) (type solid)) (layer "B.Fab"))
    (fp_line (start -0.437 1.526) (end -0.712 1.325)
      (stroke (width 0.15) (type solid)) (layer "B.Fab"))
    (fp_line (start -0.437 1.526) (end 0.688 1.526)
      (stroke (width 0.15) (type solid)) (layer "B.Fab"))
    (fp_line (start 0.688 -1.519) (end 0.688 1.52)
      (stroke (width 0.15) (type solid)) (layer "B.Fab"))
    (pad "1" smd roundrect (at -1.1 0.951) (size 1 0.6) (layers "B.Cu" "B.Paste" "B.Mask") (roundrect_rratio 0.15)
      (net 430 "Net-(Q6-G)") (pinfunction "G") (pintype "bidirectional"))
    (pad "2" smd roundrect (at -1.1 -0.949) (size 1 0.6) (layers "B.Cu" "B.Paste" "B.Mask") (roundrect_rratio 0.15)
      (net 306 "USB_5V") (pinfunction "S") (pintype "bidirectional"))
    (pad "3" smd roundrect (at 1.1 0.0005) (size 1 0.6) (layers "B.Cu" "B.Paste" "B.Mask") (roundrect_rratio 0.15)
      (net 243 "Net-(Q6-D)") (pinfunction "D") (pintype "bidirectional"))
  )
	(footprint "kria-k26-devboard-footprints:FB_0402_1005Metric" (layer "B.Cu")
    (at 110.75 86 90)
    (descr "Ferrite Bead SMD 0402")
    (tags "ferrite bead SMD 0402")
    (property "Author" "Antmicro")
    (property "License" "Apache-2.0")
    (property "MPN" "BLM15PD121SN1D")
    (property "Manufacturer" "Murata")
    (property "Sheetfile" "k26_som.kicad_sch")
    (property "Sheetname" "Xilinx K26 SOM")
    (attr smd)
    (fp_text reference "FB2" (at 1.07 1.35 270) (layer "B.SilkS")
        (effects (font (size 0.7 0.7) (thickness 0.15)) (justify left bottom mirror))
    )
    (fp_text value "FB_120Z_1.3A_0402" (at 0 -1.4 270) (layer "B.Fab") hide
        (effects (font (size 0.7 0.7) (thickness 0.15)) (justify left bottom mirror))
    )
    (fp_text user "${REFERENCE}" (at -0.95 -3.168 270) (layer "B.Fab") hide
        (effects (font (size 0.7 0.7) (thickness 0.15)) (justify left bottom mirror))
    )
    (fp_text user "Author: Antmicro" (at -0.95 -4.169 270) (layer "B.Fab") hide
        (effects (font (size 0.7 0.7) (thickness 0.15)) (justify left bottom mirror))
    )
    (fp_text user "License: Apache-2.0" (at -0.95 -5.169 270) (layer "B.Fab") hide
        (effects (font (size 0.7 0.7) (thickness 0.15)) (justify left bottom mirror))
    )
    (fp_rect (start -0.95 0.48) (end 0.95 -0.48)
      (stroke (width 0.05) (type solid)) (fill none) (layer "B.CrtYd"))
    (fp_rect (start -0.5 0.25) (end 0.5 -0.25)
      (stroke (width 0.15) (type solid)) (fill none) (layer "B.Fab"))
    (pad "1" smd roundrect (at -0.485 0 90) (size 0.59 0.64) (layers "B.Cu" "B.Paste" "B.Mask") (roundrect_rratio 0.25)
      (net 1 "GND") (pintype "passive"))
    (pad "2" smd roundrect (at 0.485 0 90) (size 0.59 0.64) (layers "B.Cu" "B.Paste" "B.Mask") (roundrect_rratio 0.25)
      (net 245 "Net-(FB2-Pad2)") (pintype "passive"))
  )
	(footprint "kria-k26-devboard-footprints:FB_0402_1005Metric" (layer "B.Cu")
    (at 105.45 86 90)
    (descr "Ferrite Bead SMD 0402")
    (tags "ferrite bead SMD 0402")
    (property "Author" "Antmicro")
    (property "License" "Apache-2.0")
    (property "MPN" "BLM15PD121SN1D")
    (property "Manufacturer" "Murata")
    (property "Sheetfile" "k26_som.kicad_sch")
    (property "Sheetname" "Xilinx K26 SOM")
    (attr smd)
    (fp_text reference "FB1" (at 1.17 -0.61 270) (layer "B.SilkS")
        (effects (font (size 0.7 0.7) (thickness 0.15)) (justify left bottom mirror))
    )
    (fp_text value "FB_120Z_1.3A_0402" (at 0 -1.4 270) (layer "B.Fab") hide
        (effects (font (size 0.7 0.7) (thickness 0.15)) (justify left bottom mirror))
    )
    (fp_text user "Author: Antmicro" (at -0.95 -4.169 270) (layer "B.Fab") hide
        (effects (font (size 0.7 0.7) (thickness 0.15)) (justify left bottom mirror))
    )
    (fp_text user "${REFERENCE}" (at -0.95 -3.168 270) (layer "B.Fab") hide
        (effects (font (size 0.7 0.7) (thickness 0.15)) (justify left bottom mirror))
    )
    (fp_text user "License: Apache-2.0" (at -0.95 -5.169 270) (layer "B.Fab") hide
        (effects (font (size 0.7 0.7) (thickness 0.15)) (justify left bottom mirror))
    )
    (fp_rect (start -0.95 0.48) (end 0.95 -0.48)
      (stroke (width 0.05) (type solid)) (fill none) (layer "B.CrtYd"))
    (fp_rect (start -0.5 0.25) (end 0.5 -0.25)
      (stroke (width 0.15) (type solid)) (fill none) (layer "B.Fab"))
    (pad "1" smd roundrect (at -0.485 0 90) (size 0.59 0.64) (layers "B.Cu" "B.Paste" "B.Mask") (roundrect_rratio 0.25)
      (net 243 "Net-(Q6-D)") (pintype "passive"))
    (pad "2" smd roundrect (at 0.485 0 90) (size 0.59 0.64) (layers "B.Cu" "B.Paste" "B.Mask") (roundrect_rratio 0.25)
      (net 244 "Net-(FB1-Pad2)") (pintype "passive"))
  )
	(footprint "kria-k26-devboard-footprints:D_SOD-323F" (layer "B.Cu")
    (at 108 90.05)
    (property "Author" "Antmicro")
    (property "License" "Apache-2.0")
    (property "MPN" "1N4148WS")
    (property "Manufacturer" "ON Semiconductor")
    (property "Sheetfile" "k26_som.kicad_sch")
    (property "Sheetname" "Xilinx K26 SOM")
    (property "ki_description" "Small Signal Fast Switching Diode")
    (attr smd)
    (fp_text reference "D3" (at 0.8 1.65 180) (layer "B.SilkS")
        (effects (font (size 0.7 0.7) (thickness 0.15)) (justify left bottom mirror))
    )
    (fp_text value "1N4148WS" (at -1.7 -1.9 180) (layer "B.Fab") hide
        (effects (font (size 0.7 0.7) (thickness 0.15)) (justify left bottom mirror))
    )
    (fp_text user "${REFERENCE}" (at -1.8 -3.2 180) (layer "B.Fab") hide
        (effects (font (size 0.7 0.7) (thickness 0.15)) (justify left bottom mirror))
    )
    (fp_text user "Author: Antmicro" (at -1.8 -4.46 180) (layer "B.Fab") hide
        (effects (font (size 0.7 0.7) (thickness 0.15)) (justify left bottom mirror))
    )
    (fp_text user "License: Apache-2.0" (at -1.8 -5.8 180) (layer "B.Fab") hide
        (effects (font (size 0.7 0.7) (thickness 0.15)) (justify left bottom mirror))
    )
    (fp_line (start -0.975 -0.748) (end -0.975 -0.45)
      (stroke (width 0.15) (type solid)) (layer "B.SilkS"))
    (fp_line (start -0.975 0.75) (end -0.975 0.45)
      (stroke (width 0.15) (type solid)) (layer "B.SilkS"))
    (fp_line (start -0.625 -0.748) (end -0.975 -0.748)
      (stroke (width 0.15) (type solid)) (layer "B.SilkS"))
    (fp_line (start -0.625 0.75) (end -0.975 0.75)
      (stroke (width 0.15) (type solid)) (layer "B.SilkS"))
    (fp_line (start -0.5 0.426) (end -0.5 -0.424)
      (stroke (width 0.15) (type solid)) (layer "B.SilkS"))
    (fp_line (start 0.623 0.75) (end 0.973 0.75)
      (stroke (width 0.15) (type solid)) (layer "B.SilkS"))
    (fp_line (start 0.973 -0.748) (end 0.623 -0.748)
      (stroke (width 0.15) (type solid)) (layer "B.SilkS"))
    (fp_line (start 0.973 -0.45) (end 0.973 -0.748)
      (stroke (width 0.15) (type solid)) (layer "B.SilkS"))
    (fp_line (start 0.973 0.75) (end 0.973 0.45)
      (stroke (width 0.15) (type solid)) (layer "B.SilkS"))
    (fp_rect (start -1.6 0.827) (end 1.599 -0.825)
      (stroke (width 0.05) (type solid)) (fill none) (layer "B.CrtYd"))
    (fp_line (start -0.85 -0.623) (end -0.85 0.625)
      (stroke (width 0.15) (type solid)) (layer "B.Fab"))
    (fp_line (start -0.85 -0.623) (end 0.848 -0.623)
      (stroke (width 0.15) (type solid)) (layer "B.Fab"))
    (fp_line (start -0.85 0.625) (end 0.848 0.625)
      (stroke (width 0.15) (type solid)) (layer "B.Fab"))
    (fp_line (start 0.848 0.625) (end 0.848 -0.623)
      (stroke (width 0.15) (type solid)) (layer "B.Fab"))
    (pad "A" smd roundrect (at 1.05 0) (size 0.8 0.6) (layers "B.Cu" "B.Paste" "B.Mask") (roundrect_rratio 0.15)
      (net 1 "GND") (pinfunction "A") (pintype "passive"))
    (pad "K" smd roundrect (at -1.051 0) (size 0.8 0.6) (layers "B.Cu" "B.Paste" "B.Mask") (roundrect_rratio 0.15)
      (net 243 "Net-(Q6-D)") (pinfunction "K") (pintype "passive"))
  )
)
